FILE_TYPE = MACRO_DRAWING;
SET COLOR_WIRE YELLOW;
SET COLOR_PROP MONO;
SET COLOR_DOT WHITE;
SET COLOR_ARC YELLOW;
SET COLOR_BODY GREEN;
SET COLOR_NOTE MONO;
SET PROP_DISPLAY VALUE;
SET PAGE_NUMBER P110;
FORCEADD INTEL_CORP_BPAGE..1
(5350 200);
FORCEPROP 1 LAST CDS_CON_LAST_MODIFIED Fri Jun 16 17:48:43 2017
J 0
(3925 525);
PAINT ORANGE (3925 525);
DISPLAY INVISIBLE (3925 525);
FORCEPROP 1 LAST CUSTOM_TXT_CDS <CURRENT_DESIGN_SHEET> OF <TOTAL_DESIGN_SHEETS>
J 0
(4850 225);
PAINT ORANGE (4850 225);
FORCEPROP 1 LAST CUSTOM_TXT_CDS <CON_LAST_MODIFIED>
J 0
(1350 300);
PAINT ORANGE (1350 300);
FORCEPROP 2 LAST CUSTOM_TXT_CDS <XR_PAGE_TITLE>
J 0
(-2540 5450);
DISPLAY 0.638298 (-2540 5450);
PAINT PINK (-2540 5450);
DISPLAY INVISIBLE (-2540 5450);
FORCEPROP 1 LAST SCH_TITLE ANCHORS - LABELS
J 0
(-2600 250);
DISPLAY 1.212766 (-2600 250);
PAINT ORANGE (-2600 250);
FORCEPROP 2 LAST CDS_LIB mstr_symbols
J 0
(5350 200);
PAINT MONO (5350 200);
DISPLAY INVISIBLE (5350 200);
FORCEPROP 2 LAST PAGE_BORDER TRUE
J 0
(-2540 5450);
DISPLAY 0.638298 (-2540 5450);
PAINT PINK (-2540 5450);
DISPLAY INVISIBLE (-2540 5450);
FORCEPROP 1 LAST COMMENT_BODY TRUE
J 0
(5362 212);
DISPLAY 0.468085 (5362 212);
PAINT GREEN (5362 212);
DISPLAY INVISIBLE (5362 212);
FORCEPROP 2 LAST CDS_XR_PAGE_TITLE CR-110 : @BASEBOARD_FAB2_LIB.BASEBOARD_FAB2(SCH_1):PAGE110
J 0
(-2540 5450);
DISPLAY 0.638298 (-2540 5450);
PAINT PINK (-2540 5450);
DISPLAY INVISIBLE (-2540 5450);
WIRE 3 682 (-2050 1850)(-2050 4750);
WIRE 3 682 (450 1850)(-2050 1850);
WIRE 3 682 (-2050 4750)(450 4750);
WIRE 3 682 (450 4750)(450 1850);
WIRE 16 273 (-2475 1625)(975 1625);
WIRE 3 682 (-2450 1550)(-2450 700);
WIRE 3 682 (750 1550)(-2450 1550);
WIRE 3 682 (-2450 700)(750 700);
WIRE 3 682 (750 700)(750 1550);
WIRE 16 273 (1125 5150)(1125 550);
FORCENOTE
BOM_COST=TEST_MFG
(-2525 525) 0;
DISPLAY LEFT (-2525 525);
DISPLAY 1.021277 (-2525 525);
PAINT PURPLE (-2525 525);
FORCENOTE
ROOM=LABELS
(-2525 600) 0;
DISPLAY LEFT (-2525 600);
DISPLAY 1.021277 (-2525 600);
PAINT PURPLE (-2525 600);
FORCENOTE
TP FAB1 DELETE ANCHORS 0321
(-1625 600) 0;
DISPLAY LEFT (-1625 600);
DISPLAY 1.021277 (-1625 600);
PAINT RED (-1625 600);
FORCENOTE
TP FAB1 DEL LABLES 0310
(-2050 4775) 0;
DISPLAY LEFT (-2050 4775);
DISPLAY 1.021277 (-2050 4775);
PAINT RED (-2050 4775);
QUIT
